# T6G (Grand Teton) — schematic netlist excerpt (pin names and nets, part order shuffled) for the footprints in the layout excerpt that follows; sources: Cadence DE-HDL packaged netlist, KiCad conversion of 04192023_DAF0TMB3IC0_F0TG_MB_C_brd_V02_OCP.brd

PR93  Q_RES  8.87K 1% EMPTY  pkg 0402LF  page 203 : A = PVDDCR_CPU1_P0_LSET5 ; B = GND
PC2218  Q_CAP  0.1UF 25V 10% X7R  pkg 0402  page 146 : A = P3V3_E1S_0_R ; B = GND

(kicad_pcb
	(version 20260206)
	(generator "pcbnew")
	(generator_version "10.0")
	(general
		(thickness 1.6)
		(legacy_teardrops no)
	)
	(paper "A4")
	(title_block
		(title "04192023_DAF0TMB3IC0_F0TG_MB_C_brd_V02_OCP.brd")
		(comment 1 "Grand Teton / footprints 3113-3114 of 8354")
	)
	(layers
		(0 "F.Cu" signal "TOP")
		(4 "In1.Cu" signal "GND")
		(6 "In2.Cu" signal "IN1")
		(8 "In3.Cu" signal "GND1")
		(10 "In4.Cu" signal "IN2")
		(12 "In5.Cu" signal "GND2")
		(14 "In6.Cu" signal "IN3")
		(16 "In7.Cu" signal "GND3")
		(18 "In8.Cu" signal "VCC")
		(20 "In9.Cu" signal "VCC1")
		(22 "In10.Cu" signal "GND4")
		(24 "In11.Cu" signal "IN4")
		(26 "In12.Cu" signal "GND5")
		(28 "In13.Cu" signal "IN5")
		(30 "In14.Cu" signal "GND6")
		(32 "In15.Cu" signal "IN6")
		(34 "In16.Cu" signal "GND7")
		(2 "B.Cu" signal "BOTTOM")
		(9 "F.Adhes" user "F.Adhesive")
		(11 "B.Adhes" user "B.Adhesive")
		(13 "F.Paste" user "Package Geometry/Pastemask Top")
		(15 "B.Paste" user "Package Geometry/Pastemask Bottom")
		(5 "F.SilkS" user "Ref Des/Silkscreen Top")
		(7 "B.SilkS" user "Ref Des/Silkscreen Bottom")
		(1 "F.Mask" user "Board Geometry/Soldermask Top")
		(3 "B.Mask" user "Board Geometry/Soldermask Bottom")
		(17 "Dwgs.User" user "User.Drawings")
		(19 "Cmts.User" user "User.Comments")
		(21 "Eco1.User" user "User.Eco1")
		(23 "Eco2.User" user "User.Eco2")
		(25 "Edge.Cuts" user "Board Geometry/Outline")
		(27 "Margin" user)
		(31 "F.CrtYd" user "Package Geometry/Place Bound Top")
		(29 "B.CrtYd" user "Package Geometry/Place Bound Bottom")
		(35 "F.Fab" user "Ref Des/Assembly Top")
		(33 "B.Fab" user "Ref Des/Assembly Bottom")
	)
	(footprint ""
		(layer "F.Cu")
		(at 218.336368 -61.072014 180)
		(property "Reference" "PC2218"
			(at 0 0 180)
			(layer "F.SilkS")
			(hide yes)
			(effects
				(font
					(size 1.27 1.27)
				)
			)
		)
		(property "Value" ""
			(at 0 0 180)
			(layer "F.Fab")
			(effects
				(font
					(size 1.27 1.27)
				)
			)
		)
		(duplicate_pad_numbers_are_jumpers no)
		(fp_line
			(start 0.7874 0.4064)
			(end -0.7874 0.4064)
			(stroke
				(width 0.1524)
				(type default)
			)
			(layer "F.SilkS")
		)
		(fp_line
			(start 0.7874 -0.4064)
			(end 0.7874 0.4064)
			(stroke
				(width 0.1524)
				(type default)
			)
			(layer "F.SilkS")
		)
		(fp_line
			(start -0.7874 0.4064)
			(end -0.7874 -0.4064)
			(stroke
				(width 0.1524)
				(type default)
			)
			(layer "F.SilkS")
		)
		(fp_line
			(start -0.7874 -0.4064)
			(end 0.7874 -0.4064)
			(stroke
				(width 0.1524)
				(type default)
			)
			(layer "F.SilkS")
		)
		(fp_line
			(start 0.67945 0.3048)
			(end 0.120396 0.3048)
			(stroke
				(width 0.1)
				(type default)
			)
			(layer "F.Fab")
		)
		(fp_line
			(start 0.67945 -0.3048)
			(end 0.67945 0.3048)
			(stroke
				(width 0.1)
				(type default)
			)
			(layer "F.Fab")
		)
		(fp_line
			(start 0.12065 -0.2794)
			(end 0.12065 -0.3048)
			(stroke
				(width 0.1)
				(type default)
			)
			(layer "F.Fab")
		)
		(fp_line
			(start 0.12065 -0.3048)
			(end 0.67945 -0.3048)
			(stroke
				(width 0.1)
				(type default)
			)
			(layer "F.Fab")
		)
		(fp_line
			(start 0.120396 0.3048)
			(end 0.120396 0.2794)
			(stroke
				(width 0.1)
				(type default)
			)
			(layer "F.Fab")
		)
		(fp_line
			(start 0.120396 0.2794)
			(end -0.12065 0.2794)
			(stroke
				(width 0.1)
				(type default)
			)
			(layer "F.Fab")
		)
		(fp_line
			(start -0.12065 0.3048)
			(end -0.67945 0.3048)
			(stroke
				(width 0.1)
				(type default)
			)
			(layer "F.Fab")
		)
		(fp_line
			(start -0.12065 0.2794)
			(end -0.12065 0.3048)
			(stroke
				(width 0.1)
				(type default)
			)
			(layer "F.Fab")
		)
		(fp_line
			(start -0.12065 -0.2794)
			(end 0.12065 -0.2794)
			(stroke
				(width 0.1)
				(type default)
			)
			(layer "F.Fab")
		)
		(fp_line
			(start -0.12065 -0.305054)
			(end -0.12065 -0.2794)
			(stroke
				(width 0.1)
				(type default)
			)
			(layer "F.Fab")
		)
		(fp_line
			(start -0.67945 0.3048)
			(end -0.67945 -0.305054)
			(stroke
				(width 0.1)
				(type default)
			)
			(layer "F.Fab")
		)
		(fp_line
			(start -0.67945 -0.305054)
			(end -0.12065 -0.305054)
			(stroke
				(width 0.1)
				(type default)
			)
			(layer "F.Fab")
		)
		(pad "1" smd circle
			(at -0.40005 0 180)
			(size 0 0)
			(layers "F.Cu" "F.Mask" "F.Paste")
			(net "P3V3_E1S_0_R")
		)
		(pad "2" smd circle
			(at 0.40005 0 180)
			(size 0 0)
			(layers "F.Cu" "F.Mask" "F.Paste")
			(net "GND")
		)
	)
	(footprint ""
		(layer "F.Cu")
		(at 342.085676 -340.236048)
		(property "Reference" "PR93"
			(at 0 0 0)
			(layer "F.SilkS")
			(hide yes)
			(effects
				(font
					(size 1.27 1.27)
				)
			)
		)
		(property "Value" ""
			(at 0 0 0)
			(layer "F.Fab")
			(effects
				(font
					(size 1.27 1.27)
				)
			)
		)
		(duplicate_pad_numbers_are_jumpers no)
		(fp_line
			(start -0.7874 -0.4064)
			(end 0.7874 -0.4064)
			(stroke
				(width 0.1524)
				(type default)
			)
			(layer "F.SilkS")
		)
		(fp_line
			(start -0.7874 0.4064)
			(end -0.7874 -0.4064)
			(stroke
				(width 0.1524)
				(type default)
			)
			(layer "F.SilkS")
		)
		(fp_line
			(start 0.7874 -0.4064)
			(end 0.7874 0.4064)
			(stroke
				(width 0.1524)
				(type default)
			)
			(layer "F.SilkS")
		)
		(fp_line
			(start 0.7874 0.4064)
			(end -0.7874 0.4064)
			(stroke
				(width 0.1524)
				(type default)
			)
			(layer "F.SilkS")
		)
		(fp_line
			(start -0.67945 -0.305054)
			(end -0.12065 -0.305054)
			(stroke
				(width 0.1)
				(type default)
			)
			(layer "F.Fab")
		)
		(fp_line
			(start -0.67945 0.3048)
			(end -0.67945 -0.305054)
			(stroke
				(width 0.1)
				(type default)
			)
			(layer "F.Fab")
		)
		(fp_line
			(start -0.12065 -0.305054)
			(end -0.12065 -0.2794)
			(stroke
				(width 0.1)
				(type default)
			)
			(layer "F.Fab")
		)
		(fp_line
			(start -0.12065 -0.2794)
			(end 0.12065 -0.2794)
			(stroke
				(width 0.1)
				(type default)
			)
			(layer "F.Fab")
		)
		(fp_line
			(start -0.12065 0.2794)
			(end -0.12065 0.3048)
			(stroke
				(width 0.1)
				(type default)
			)
			(layer "F.Fab")
		)
		(fp_line
			(start -0.12065 0.3048)
			(end -0.67945 0.3048)
			(stroke
				(width 0.1)
				(type default)
			)
			(layer "F.Fab")
		)
		(fp_line
			(start 0.120396 0.2794)
			(end -0.12065 0.2794)
			(stroke
				(width 0.1)
				(type default)
			)
			(layer "F.Fab")
		)
		(fp_line
			(start 0.120396 0.3048)
			(end 0.120396 0.2794)
			(stroke
				(width 0.1)
				(type default)
			)
			(layer "F.Fab")
		)
		(fp_line
			(start 0.12065 -0.3048)
			(end 0.67945 -0.3048)
			(stroke
				(width 0.1)
				(type default)
			)
			(layer "F.Fab")
		)
		(fp_line
			(start 0.12065 -0.2794)
			(end 0.12065 -0.3048)
			(stroke
				(width 0.1)
				(type default)
			)
			(layer "F.Fab")
		)
		(fp_line
			(start 0.67945 -0.3048)
			(end 0.67945 0.3048)
			(stroke
				(width 0.1)
				(type default)
			)
			(layer "F.Fab")
		)
		(fp_line
			(start 0.67945 0.3048)
			(end 0.120396 0.3048)
			(stroke
				(width 0.1)
				(type default)
			)
			(layer "F.Fab")
		)
		(pad "1" smd circle
			(at -0.40005 0)
			(size 0 0)
			(layers "F.Cu" "F.Mask" "F.Paste")
			(net "PVDDCR_CPU1_P0_LSET5")
		)
		(pad "2" smd circle
			(at 0.40005 0)
			(size 0 0)
			(layers "F.Cu" "F.Mask" "F.Paste")
			(net "GND")
		)
	)
)
